# T6G (Grand Teton) — schematic netlist excerpt (pin names and nets, part order shuffled) for the footprints in the layout excerpt that follows; sources: Cadence DE-HDL packaged netlist, KiCad conversion of 04192023_DAF0TMB3IC0_F0TG_MB_C_brd_V02_OCP.brd

R424  Q_RES  2.2K 5% CHIP  pkg 0402LF  page 28 : A = PVDD18_S5_P0 ; B = CPU0_PWR_BTN_N
R1527  Q_RES  1K 1% CHIP  pkg 0402LF  page 83 : A = PRSNT_HDT_N ; B = P3V3_AUX

(kicad_pcb
	(version 20260206)
	(generator "pcbnew")
	(generator_version "10.0")
	(general
		(thickness 1.6)
		(legacy_teardrops no)
	)
	(paper "A4")
	(title_block
		(title "04192023_DAF0TMB3IC0_F0TG_MB_C_brd_V02_OCP.brd")
		(comment 1 "Grand Teton / footprints 3795-3796 of 8354")
	)
	(layers
		(0 "F.Cu" signal "TOP")
		(4 "In1.Cu" signal "GND")
		(6 "In2.Cu" signal "IN1")
		(8 "In3.Cu" signal "GND1")
		(10 "In4.Cu" signal "IN2")
		(12 "In5.Cu" signal "GND2")
		(14 "In6.Cu" signal "IN3")
		(16 "In7.Cu" signal "GND3")
		(18 "In8.Cu" signal "VCC")
		(20 "In9.Cu" signal "VCC1")
		(22 "In10.Cu" signal "GND4")
		(24 "In11.Cu" signal "IN4")
		(26 "In12.Cu" signal "GND5")
		(28 "In13.Cu" signal "IN5")
		(30 "In14.Cu" signal "GND6")
		(32 "In15.Cu" signal "IN6")
		(34 "In16.Cu" signal "GND7")
		(2 "B.Cu" signal "BOTTOM")
		(9 "F.Adhes" user "F.Adhesive")
		(11 "B.Adhes" user "B.Adhesive")
		(13 "F.Paste" user "Package Geometry/Pastemask Top")
		(15 "B.Paste" user "Package Geometry/Pastemask Bottom")
		(5 "F.SilkS" user "Ref Des/Silkscreen Top")
		(7 "B.SilkS" user "Ref Des/Silkscreen Bottom")
		(1 "F.Mask" user "Board Geometry/Soldermask Top")
		(3 "B.Mask" user "Board Geometry/Soldermask Bottom")
		(17 "Dwgs.User" user "User.Drawings")
		(19 "Cmts.User" user "User.Comments")
		(21 "Eco1.User" user "User.Eco1")
		(23 "Eco2.User" user "User.Eco2")
		(25 "Edge.Cuts" user "Board Geometry/Outline")
		(27 "Margin" user)
		(31 "F.CrtYd" user "Package Geometry/Place Bound Top")
		(29 "B.CrtYd" user "Package Geometry/Place Bound Bottom")
		(35 "F.Fab" user "Ref Des/Assembly Top")
		(33 "B.Fab" user "Ref Des/Assembly Bottom")
	)
	(footprint ""
		(layer "F.Cu")
		(at 197.269608 -124.801376)
		(property "Reference" "R1527"
			(at 0 0 0)
			(layer "F.SilkS")
			(hide yes)
			(effects
				(font
					(size 1.27 1.27)
				)
			)
		)
		(property "Value" ""
			(at 0 0 0)
			(layer "F.Fab")
			(effects
				(font
					(size 1.27 1.27)
				)
			)
		)
		(duplicate_pad_numbers_are_jumpers no)
		(fp_line
			(start -0.7874 -0.4064)
			(end 0.7874 -0.4064)
			(stroke
				(width 0.1524)
				(type default)
			)
			(layer "F.SilkS")
		)
		(fp_line
			(start -0.7874 0.4064)
			(end -0.7874 -0.4064)
			(stroke
				(width 0.1524)
				(type default)
			)
			(layer "F.SilkS")
		)
		(fp_line
			(start 0.7874 -0.4064)
			(end 0.7874 0.4064)
			(stroke
				(width 0.1524)
				(type default)
			)
			(layer "F.SilkS")
		)
		(fp_line
			(start 0.7874 0.4064)
			(end -0.7874 0.4064)
			(stroke
				(width 0.1524)
				(type default)
			)
			(layer "F.SilkS")
		)
		(fp_line
			(start -0.67945 -0.305054)
			(end -0.12065 -0.305054)
			(stroke
				(width 0.1)
				(type default)
			)
			(layer "F.Fab")
		)
		(fp_line
			(start -0.67945 0.3048)
			(end -0.67945 -0.305054)
			(stroke
				(width 0.1)
				(type default)
			)
			(layer "F.Fab")
		)
		(fp_line
			(start -0.12065 -0.305054)
			(end -0.12065 -0.2794)
			(stroke
				(width 0.1)
				(type default)
			)
			(layer "F.Fab")
		)
		(fp_line
			(start -0.12065 -0.2794)
			(end 0.12065 -0.2794)
			(stroke
				(width 0.1)
				(type default)
			)
			(layer "F.Fab")
		)
		(fp_line
			(start -0.12065 0.2794)
			(end -0.12065 0.3048)
			(stroke
				(width 0.1)
				(type default)
			)
			(layer "F.Fab")
		)
		(fp_line
			(start -0.12065 0.3048)
			(end -0.67945 0.3048)
			(stroke
				(width 0.1)
				(type default)
			)
			(layer "F.Fab")
		)
		(fp_line
			(start 0.120396 0.2794)
			(end -0.12065 0.2794)
			(stroke
				(width 0.1)
				(type default)
			)
			(layer "F.Fab")
		)
		(fp_line
			(start 0.120396 0.3048)
			(end 0.120396 0.2794)
			(stroke
				(width 0.1)
				(type default)
			)
			(layer "F.Fab")
		)
		(fp_line
			(start 0.12065 -0.3048)
			(end 0.67945 -0.3048)
			(stroke
				(width 0.1)
				(type default)
			)
			(layer "F.Fab")
		)
		(fp_line
			(start 0.12065 -0.2794)
			(end 0.12065 -0.3048)
			(stroke
				(width 0.1)
				(type default)
			)
			(layer "F.Fab")
		)
		(fp_line
			(start 0.67945 -0.3048)
			(end 0.67945 0.3048)
			(stroke
				(width 0.1)
				(type default)
			)
			(layer "F.Fab")
		)
		(fp_line
			(start 0.67945 0.3048)
			(end 0.120396 0.3048)
			(stroke
				(width 0.1)
				(type default)
			)
			(layer "F.Fab")
		)
		(pad "1" smd circle
			(at -0.40005 0)
			(size 0 0)
			(layers "F.Cu" "F.Mask" "F.Paste")
			(net "PRSNT_HDT_N")
		)
		(pad "2" smd circle
			(at 0.40005 0)
			(size 0 0)
			(layers "F.Cu" "F.Mask" "F.Paste")
			(net "P3V3_AUX")
		)
	)
	(footprint ""
		(layer "F.Cu")
		(at 293.038022 -53.29809)
		(property "Reference" "R424"
			(at 0 0 0)
			(layer "F.SilkS")
			(hide yes)
			(effects
				(font
					(size 1.27 1.27)
				)
			)
		)
		(property "Value" ""
			(at 0 0 0)
			(layer "F.Fab")
			(effects
				(font
					(size 1.27 1.27)
				)
			)
		)
		(duplicate_pad_numbers_are_jumpers no)
		(fp_line
			(start -0.7874 -0.4064)
			(end 0.7874 -0.4064)
			(stroke
				(width 0.1524)
				(type default)
			)
			(layer "F.SilkS")
		)
		(fp_line
			(start -0.7874 0.4064)
			(end -0.7874 -0.4064)
			(stroke
				(width 0.1524)
				(type default)
			)
			(layer "F.SilkS")
		)
		(fp_line
			(start 0.7874 -0.4064)
			(end 0.7874 0.4064)
			(stroke
				(width 0.1524)
				(type default)
			)
			(layer "F.SilkS")
		)
		(fp_line
			(start 0.7874 0.4064)
			(end -0.7874 0.4064)
			(stroke
				(width 0.1524)
				(type default)
			)
			(layer "F.SilkS")
		)
		(fp_line
			(start -0.67945 -0.305054)
			(end -0.12065 -0.305054)
			(stroke
				(width 0.1)
				(type default)
			)
			(layer "F.Fab")
		)
		(fp_line
			(start -0.67945 0.3048)
			(end -0.67945 -0.305054)
			(stroke
				(width 0.1)
				(type default)
			)
			(layer "F.Fab")
		)
		(fp_line
			(start -0.12065 -0.305054)
			(end -0.12065 -0.2794)
			(stroke
				(width 0.1)
				(type default)
			)
			(layer "F.Fab")
		)
		(fp_line
			(start -0.12065 -0.2794)
			(end 0.12065 -0.2794)
			(stroke
				(width 0.1)
				(type default)
			)
			(layer "F.Fab")
		)
		(fp_line
			(start -0.12065 0.2794)
			(end -0.12065 0.3048)
			(stroke
				(width 0.1)
				(type default)
			)
			(layer "F.Fab")
		)
		(fp_line
			(start -0.12065 0.3048)
			(end -0.67945 0.3048)
			(stroke
				(width 0.1)
				(type default)
			)
			(layer "F.Fab")
		)
		(fp_line
			(start 0.120396 0.2794)
			(end -0.12065 0.2794)
			(stroke
				(width 0.1)
				(type default)
			)
			(layer "F.Fab")
		)
		(fp_line
			(start 0.120396 0.3048)
			(end 0.120396 0.2794)
			(stroke
				(width 0.1)
				(type default)
			)
			(layer "F.Fab")
		)
		(fp_line
			(start 0.12065 -0.3048)
			(end 0.67945 -0.3048)
			(stroke
				(width 0.1)
				(type default)
			)
			(layer "F.Fab")
		)
		(fp_line
			(start 0.12065 -0.2794)
			(end 0.12065 -0.3048)
			(stroke
				(width 0.1)
				(type default)
			)
			(layer "F.Fab")
		)
		(fp_line
			(start 0.67945 -0.3048)
			(end 0.67945 0.3048)
			(stroke
				(width 0.1)
				(type default)
			)
			(layer "F.Fab")
		)
		(fp_line
			(start 0.67945 0.3048)
			(end 0.120396 0.3048)
			(stroke
				(width 0.1)
				(type default)
			)
			(layer "F.Fab")
		)
		(pad "1" smd circle
			(at -0.40005 0)
			(size 0 0)
			(layers "F.Cu" "F.Mask" "F.Paste")
			(net "PVDD18_S5_P0")
		)
		(pad "2" smd circle
			(at 0.40005 0)
			(size 0 0)
			(layers "F.Cu" "F.Mask" "F.Paste")
			(net "CPU0_PWR_BTN_N")
		)
	)
)
